(kicad_pcb
	(version 20241229)
	(generator "pcbnew")
	(generator_version "9.0")
	(general
		(thickness 1.599998)
		(legacy_teardrops no)
	)
	(paper "A4")
	(title_block
		(date "2023-02-12")
		(rev "1.1.5")
		(comment 9 "footprints 268-274 of 473")
	)
	(layers
		(0 "F.Cu" signal)
		(4 "In1.Cu" power "In1.GND")
		(6 "In2.Cu" signal)
		(8 "In3.Cu" power "In3.GND")
		(10 "In4.Cu" power "In4.VCC")
		(12 "In5.Cu" signal)
		(14 "In6.Cu" power "In6.VCC")
		(2 "B.Cu" signal)
		(9 "F.Adhes" user "F.Adhesive")
		(11 "B.Adhes" user "B.Adhesive")
		(13 "F.Paste" user)
		(15 "B.Paste" user)
		(5 "F.SilkS" user "F.Silkscreen")
		(7 "B.SilkS" user "B.Silkscreen")
		(1 "F.Mask" user)
		(3 "B.Mask" user)
		(17 "Dwgs.User" user "User.Drawings")
		(19 "Cmts.User" user "User.Comments")
		(21 "Eco1.User" user "User.Eco1")
		(23 "Eco2.User" user "User.Eco2")
		(25 "Edge.Cuts" user)
		(27 "Margin" user)
		(31 "F.CrtYd" user "F.Courtyard")
		(29 "B.CrtYd" user "B.Courtyard")
		(35 "F.Fab" user)
		(33 "B.Fab" user)
	)
	(footprint "antmicro-footprints:C_0603_1608Metric"
		(layer "F.Cu")
		(at 134.3 52.7 90)
		(descr "Capacitor SMD 0603")
		(tags "capacitor 0603")
		(property "Reference" "C196"
			(at 1 0.3 90)
			(layer "F.SilkS")
			(effects
				(font
					(size 0.7 0.7)
					(thickness 0.15)
				)
				(justify left bottom)
			)
		)
		(property "Value" "C_22u_0603"
			(at 0 1.6 90)
			(layer "F.Fab")
			(effects
				(font
					(size 0.7 0.7)
					(thickness 0.15)
				)
				(justify left bottom)
			)
		)
		(property "Description" " "
			(at 0 0 90)
			(layer "F.Fab")
			(hide yes)
			(effects
				(font
					(size 1.27 1.27)
					(thickness 0.15)
				)
			)
		)
		(property "Author" "Antmicro"
			(at 187 -81.6 0)
			(layer "F.Fab")
			(hide yes)
			(effects
				(font
					(size 1 1)
					(thickness 0.15)
				)
			)
		)
		(property "Dielectric" ""
			(at 187 -81.6 0)
			(layer "F.Fab")
			(hide yes)
			(effects
				(font
					(size 1 1)
					(thickness 0.15)
				)
			)
		)
		(property "License" "Apache-2.0"
			(at 187 -81.6 0)
			(layer "F.Fab")
			(hide yes)
			(effects
				(font
					(size 1 1)
					(thickness 0.15)
				)
			)
		)
		(property "MPN" "GRM188R60J226MEA0D"
			(at 187 -81.6 0)
			(layer "F.Fab")
			(hide yes)
			(effects
				(font
					(size 1 1)
					(thickness 0.15)
				)
			)
		)
		(property "Manufacturer" "Murata"
			(at 187 -81.6 0)
			(layer "F.Fab")
			(hide yes)
			(effects
				(font
					(size 1 1)
					(thickness 0.15)
				)
			)
		)
		(property "Val" "22u"
			(at 187 -81.6 0)
			(layer "F.Fab")
			(hide yes)
			(effects
				(font
					(size 1 1)
					(thickness 0.15)
				)
			)
		)
		(property "Voltage" ""
			(at 187 -81.6 0)
			(layer "F.Fab")
			(hide yes)
			(effects
				(font
					(size 1 1)
					(thickness 0.15)
				)
			)
		)
		(sheetname "Supply")
		(sheetfile "supply.kicad_sch")
		(attr exclude_from_pos_files exclude_from_bom dnp)
		(fp_line
			(start -0.3 -0.3)
			(end 0.3 -0.3)
			(stroke
				(width 0.15)
				(type solid)
			)
			(layer "F.SilkS")
		)
		(fp_line
			(start -0.3 0.3)
			(end 0.3 0.3)
			(stroke
				(width 0.15)
				(type solid)
			)
			(layer "F.SilkS")
		)
		(fp_rect
			(start -1.24 -0.7)
			(end 1.24 0.7)
			(stroke
				(width 0.05)
				(type solid)
			)
			(fill no)
			(layer "F.CrtYd")
		)
		(fp_rect
			(start -0.8 -0.4)
			(end 0.8 0.4)
			(stroke
				(width 0.15)
				(type solid)
			)
			(fill no)
			(layer "F.Fab")
		)
		(pad "1" smd roundrect
			(at -0.7 0 90)
			(size 0.6 0.8)
			(layers "F.Cu" "F.Mask" "F.Paste")
			(roundrect_rratio 0.2)
			(net 550 "VDD1V1")
			(pintype "passive")
		)
		(pad "2" smd roundrect
			(at 0.7 0 90)
			(size 0.6 0.8)
			(layers "F.Cu" "F.Mask" "F.Paste")
			(roundrect_rratio 0.2)
			(net 5 "GND")
			(pintype "passive")
		)
	)
	(footprint "antmicro-footprints:R_0402_1005Metric"
		(layer "F.Cu")
		(at 111.362806 90.974)
		(descr "Resistor SMD 0402")
		(tags "resistor SMD 0402")
		(property "Reference" "R136"
			(at -3.662806 0.326 0)
			(layer "F.SilkS")
			(effects
				(font
					(size 0.7 0.7)
					(thickness 0.15)
				)
				(justify left bottom)
			)
		)
		(property "Value" "R_31k6_0402"
			(at 0 1.4 0)
			(layer "F.Fab")
			(effects
				(font
					(size 0.7 0.7)
					(thickness 0.15)
				)
				(justify left bottom)
			)
		)
		(property "Description" "31k6 resistor in 0402 package with 1% tolerance"
			(at 0 0 0)
			(layer "F.Fab")
			(hide yes)
			(effects
				(font
					(size 1.27 1.27)
					(thickness 0.15)
				)
			)
		)
		(property "Author" "Antmicro"
			(at 0 0 0)
			(layer "F.Fab")
			(hide yes)
			(effects
				(font
					(size 1 1)
					(thickness 0.15)
				)
			)
		)
		(property "License" "Apache-2.0"
			(at 0 0 0)
			(layer "F.Fab")
			(hide yes)
			(effects
				(font
					(size 1 1)
					(thickness 0.15)
				)
			)
		)
		(property "MPN" "CR0402-FX-3162GLF"
			(at 0 0 0)
			(layer "F.Fab")
			(hide yes)
			(effects
				(font
					(size 1 1)
					(thickness 0.15)
				)
			)
		)
		(property "Manufacturer" "Bourns"
			(at 0 0 0)
			(layer "F.Fab")
			(hide yes)
			(effects
				(font
					(size 1 1)
					(thickness 0.15)
				)
			)
		)
		(property "Tolerance" "1%"
			(at 0 0 0)
			(layer "F.Fab")
			(hide yes)
			(effects
				(font
					(size 1 1)
					(thickness 0.15)
				)
			)
		)
		(property "Val" "31k6"
			(at 0 0 0)
			(layer "F.Fab")
			(hide yes)
			(effects
				(font
					(size 1 1)
					(thickness 0.15)
				)
			)
		)
		(sheetname "Supply")
		(sheetfile "supply.kicad_sch")
		(attr smd)
		(fp_rect
			(start -0.93 -0.47)
			(end 0.93 0.47)
			(stroke
				(width 0.05)
				(type solid)
			)
			(fill no)
			(layer "F.CrtYd")
		)
		(fp_rect
			(start -0.5 -0.25)
			(end 0.5 0.25)
			(stroke
				(width 0.15)
				(type solid)
			)
			(fill no)
			(layer "F.Fab")
		)
		(pad "1" smd roundrect
			(at -0.485 0)
			(size 0.59 0.64)
			(layers "F.Cu" "F.Mask" "F.Paste")
			(roundrect_rratio 0.25)
			(net 583 "/Supply/1V8_REG")
			(pintype "passive")
		)
		(pad "2" smd roundrect
			(at 0.485 0)
			(size 0.59 0.64)
			(layers "F.Cu" "F.Mask" "F.Paste")
			(roundrect_rratio 0.25)
			(net 600 "/Supply/1V8_FB")
			(pintype "passive")
		)
	)
	(footprint "antmicro-footprints:R_0402_1005Metric"
		(layer "F.Cu")
		(at 185.1 111.85 90)
		(descr "Resistor SMD 0402")
		(tags "resistor SMD 0402")
		(property "Reference" "R141"
			(at 0.75 0.4 90)
			(layer "F.SilkS")
			(effects
				(font
					(size 0.7 0.7)
					(thickness 0.15)
				)
				(justify left bottom)
			)
		)
		(property "Value" "R_10k_0402"
			(at 0 1.4 90)
			(layer "F.Fab")
			(effects
				(font
					(size 0.7 0.7)
					(thickness 0.15)
				)
				(justify left bottom)
			)
		)
		(property "Description" "10k resistor in 0402 package with 1% tolerance"
			(at 0 0 90)
			(layer "F.Fab")
			(hide yes)
			(effects
				(font
					(size 1.27 1.27)
					(thickness 0.15)
				)
			)
		)
		(property "Author" "Antmicro"
			(at 296.95 -73.25 0)
			(layer "F.Fab")
			(hide yes)
			(effects
				(font
					(size 1 1)
					(thickness 0.15)
				)
			)
		)
		(property "License" "Apache-2.0"
			(at 296.95 -73.25 0)
			(layer "F.Fab")
			(hide yes)
			(effects
				(font
					(size 1 1)
					(thickness 0.15)
				)
			)
		)
		(property "MPN" "CR0402-FX-1002GLF"
			(at 296.95 -73.25 0)
			(layer "F.Fab")
			(hide yes)
			(effects
				(font
					(size 1 1)
					(thickness 0.15)
				)
			)
		)
		(property "Manufacturer" "Bourns"
			(at 296.95 -73.25 0)
			(layer "F.Fab")
			(hide yes)
			(effects
				(font
					(size 1 1)
					(thickness 0.15)
				)
			)
		)
		(property "Tolerance" "1%"
			(at 296.95 -73.25 0)
			(layer "F.Fab")
			(hide yes)
			(effects
				(font
					(size 1 1)
					(thickness 0.15)
				)
			)
		)
		(property "Val" "10k"
			(at 296.95 -73.25 0)
			(layer "F.Fab")
			(hide yes)
			(effects
				(font
					(size 1 1)
					(thickness 0.15)
				)
			)
		)
		(sheetname "Supply")
		(sheetfile "supply.kicad_sch")
		(attr smd)
		(fp_rect
			(start -0.93 -0.47)
			(end 0.93 0.47)
			(stroke
				(width 0.05)
				(type solid)
			)
			(fill no)
			(layer "F.CrtYd")
		)
		(fp_rect
			(start -0.5 -0.25)
			(end 0.5 0.25)
			(stroke
				(width 0.15)
				(type solid)
			)
			(fill no)
			(layer "F.Fab")
		)
		(pad "1" smd roundrect
			(at -0.485 0 90)
			(size 0.59 0.64)
			(layers "F.Cu" "F.Mask" "F.Paste")
			(roundrect_rratio 0.25)
			(net 601 "/Supply/1V2_FB")
			(pintype "passive")
		)
		(pad "2" smd roundrect
			(at 0.485 0 90)
			(size 0.59 0.64)
			(layers "F.Cu" "F.Mask" "F.Paste")
			(roundrect_rratio 0.25)
			(net 5 "GND")
			(pintype "passive")
		)
	)
	(footprint "antmicro-footprints:C_0402_1005Metric"
		(layer "F.Cu")
		(at 111.725 95.249 180)
		(descr "Capacitor SMD 0402")
		(tags "capacitor SMD 0402")
		(property "Reference" "C177"
			(at 3.625 -0.351 180)
			(layer "F.SilkS")
			(effects
				(font
					(size 0.7 0.7)
					(thickness 0.15)
				)
				(justify left bottom)
			)
		)
		(property "Value" "C_1u_0402"
			(at 0 1.4 180)
			(layer "F.Fab")
			(effects
				(font
					(size 0.7 0.7)
					(thickness 0.15)
				)
				(justify left bottom)
			)
		)
		(property "Description" " "
			(at 0 0 180)
			(layer "F.Fab")
			(hide yes)
			(effects
				(font
					(size 1.27 1.27)
					(thickness 0.15)
				)
			)
		)
		(property "Author" "Antmicro"
			(at 223.45 190.498 0)
			(layer "F.Fab")
			(hide yes)
			(effects
				(font
					(size 1 1)
					(thickness 0.15)
				)
			)
		)
		(property "Dielectric" ""
			(at 223.45 190.498 0)
			(layer "F.Fab")
			(hide yes)
			(effects
				(font
					(size 1 1)
					(thickness 0.15)
				)
			)
		)
		(property "License" "Apache-2.0"
			(at 223.45 190.498 0)
			(layer "F.Fab")
			(hide yes)
			(effects
				(font
					(size 1 1)
					(thickness 0.15)
				)
			)
		)
		(property "MPN" "C1005X6S1A105K050BC"
			(at 223.45 190.498 0)
			(layer "F.Fab")
			(hide yes)
			(effects
				(font
					(size 1 1)
					(thickness 0.15)
				)
			)
		)
		(property "Manufacturer" "TDK"
			(at 223.45 190.498 0)
			(layer "F.Fab")
			(hide yes)
			(effects
				(font
					(size 1 1)
					(thickness 0.15)
				)
			)
		)
		(property "Val" "1u"
			(at 223.45 190.498 0)
			(layer "F.Fab")
			(hide yes)
			(effects
				(font
					(size 1 1)
					(thickness 0.15)
				)
			)
		)
		(property "Voltage" ""
			(at 223.45 190.498 0)
			(layer "F.Fab")
			(hide yes)
			(effects
				(font
					(size 1 1)
					(thickness 0.15)
				)
			)
		)
		(sheetname "Supply")
		(sheetfile "supply.kicad_sch")
		(attr smd)
		(fp_rect
			(start -0.94 -0.47)
			(end 0.94 0.47)
			(stroke
				(width 0.05)
				(type solid)
			)
			(fill no)
			(layer "F.CrtYd")
		)
		(fp_rect
			(start -0.499 -0.249)
			(end 0.499 0.249)
			(stroke
				(width 0.15)
				(type solid)
			)
			(fill no)
			(layer "F.Fab")
		)
		(pad "1" smd roundrect
			(at -0.484 0 180)
			(size 0.59 0.64)
			(layers "F.Cu" "F.Mask" "F.Paste")
			(roundrect_rratio 0.25)
			(net 576 "/Supply/3V3_REG")
			(pintype "passive")
		)
		(pad "2" smd roundrect
			(at 0.484 0 180)
			(size 0.59 0.64)
			(layers "F.Cu" "F.Mask" "F.Paste")
			(roundrect_rratio 0.25)
			(net 5 "GND")
			(pintype "passive")
		)
	)
	(footprint "antmicro-footprints:R_0805_2012Metric"
		(layer "F.Cu")
		(at 113.797806 82.274)
		(property "Reference" "R144"
			(at 0 -1 0)
			(layer "F.SilkS")
			(effects
				(font
					(size 0.7 0.7)
					(thickness 0.15)
				)
				(justify left bottom)
			)
		)
		(property "Value" "R_0R_0805"
			(at 0 1.8 0)
			(layer "F.Fab")
			(effects
				(font
					(size 0.7 0.7)
					(thickness 0.15)
				)
				(justify left bottom)
			)
		)
		(property "Description" "0R resistor in 0805 package with unspecified tolerance"
			(at 0 0 0)
			(layer "F.Fab")
			(hide yes)
			(effects
				(font
					(size 1.27 1.27)
					(thickness 0.15)
				)
			)
		)
		(property "Author" "Antmicro"
			(at 0 0 0)
			(layer "F.Fab")
			(hide yes)
			(effects
				(font
					(size 1 1)
					(thickness 0.15)
				)
			)
		)
		(property "Current" "2.5A"
			(at 0 0 0)
			(layer "F.Fab")
			(hide yes)
			(effects
				(font
					(size 1 1)
					(thickness 0.15)
				)
			)
		)
		(property "License" "Apache-2.0"
			(at 0 0 0)
			(layer "F.Fab")
			(hide yes)
			(effects
				(font
					(size 1 1)
					(thickness 0.15)
				)
			)
		)
		(property "MPN" "CRCW08050000Z0EA"
			(at 0 0 0)
			(layer "F.Fab")
			(hide yes)
			(effects
				(font
					(size 1 1)
					(thickness 0.15)
				)
			)
		)
		(property "Manufacturer" "Vishay"
			(at 0 0 0)
			(layer "F.Fab")
			(hide yes)
			(effects
				(font
					(size 1 1)
					(thickness 0.15)
				)
			)
		)
		(property "Tolerance" ""
			(at 0 0 0)
			(layer "F.Fab")
			(hide yes)
			(effects
				(font
					(size 1 1)
					(thickness 0.15)
				)
			)
		)
		(property "Val" "0R"
			(at 0 0 0)
			(layer "F.Fab")
			(hide yes)
			(effects
				(font
					(size 1 1)
					(thickness 0.15)
				)
			)
		)
		(sheetname "Supply")
		(sheetfile "supply.kicad_sch")
		(attr smd)
		(fp_line
			(start -0.32 0.699)
			(end 0.28 0.699)
			(stroke
				(width 0.15)
				(type solid)
			)
			(layer "F.SilkS")
		)
		(fp_line
			(start -0.3 -0.701)
			(end 0.298 -0.701)
			(stroke
				(width 0.15)
				(type solid)
			)
			(layer "F.SilkS")
		)
		(fp_rect
			(start -1.75 -0.85)
			(end 1.75 0.85)
			(stroke
				(width 0.05)
				(type solid)
			)
			(fill no)
			(layer "F.CrtYd")
		)
		(fp_line
			(start -0.951 -0.682)
			(end 0.949 -0.682)
			(stroke
				(width 0.15)
				(type solid)
			)
			(layer "F.Fab")
		)
		(fp_line
			(start -0.951 -0.677)
			(end -0.951 0.675)
			(stroke
				(width 0.15)
				(type solid)
			)
			(layer "F.Fab")
		)
		(fp_line
			(start -0.951 0.68)
			(end 0.949 0.68)
			(stroke
				(width 0.15)
				(type solid)
			)
			(layer "F.Fab")
		)
		(fp_line
			(start 0.949 -0.677)
			(end 0.949 0.675)
			(stroke
				(width 0.15)
				(type solid)
			)
			(layer "F.Fab")
		)
		(pad "1" smd roundrect
			(at -1.1 -0.001)
			(size 1 1.4)
			(layers "F.Cu" "F.Mask" "F.Paste")
			(roundrect_rratio 0.15)
			(net 583 "/Supply/1V8_REG")
			(pintype "passive")
		)
		(pad "2" smd roundrect
			(at 1.1 -0.001)
			(size 1 1.4)
			(layers "F.Cu" "F.Mask" "F.Paste")
			(roundrect_rratio 0.15)
			(net 460 "1V8_SYS")
			(pintype "passive")
		)
	)
	(footprint "antmicro-footprints:R_0402_1005Metric"
		(layer "F.Cu")
		(at 140.1825 89.599)
		(descr "Resistor SMD 0402")
		(tags "resistor SMD 0402")
		(property "Reference" "R101"
			(at -3.6825 -0.799 0)
			(layer "F.SilkS")
			(effects
				(font
					(size 0.7 0.7)
					(thickness 0.15)
				)
				(justify left bottom)
			)
		)
		(property "Value" "R_330R_0402"
			(at 0 1.4 0)
			(layer "F.Fab")
			(effects
				(font
					(size 0.7 0.7)
					(thickness 0.15)
				)
				(justify left bottom)
			)
		)
		(property "Description" "330R resistor in 0402 package with 1% tolerance"
			(at 0 0 0)
			(layer "F.Fab")
			(hide yes)
			(effects
				(font
					(size 1.27 1.27)
					(thickness 0.15)
				)
			)
		)
		(property "Author" "Antmicro"
			(at 0 0 0)
			(layer "F.Fab")
			(hide yes)
			(effects
				(font
					(size 1 1)
					(thickness 0.15)
				)
			)
		)
		(property "License" "Apache-2.0"
			(at 0 0 0)
			(layer "F.Fab")
			(hide yes)
			(effects
				(font
					(size 1 1)
					(thickness 0.15)
				)
			)
		)
		(property "MPN" "CR0402-FX-3300GLF"
			(at 0 0 0)
			(layer "F.Fab")
			(hide yes)
			(effects
				(font
					(size 1 1)
					(thickness 0.15)
				)
			)
		)
		(property "Manufacturer" "Bourns"
			(at 0 0 0)
			(layer "F.Fab")
			(hide yes)
			(effects
				(font
					(size 1 1)
					(thickness 0.15)
				)
			)
		)
		(property "Tolerance" "1%"
			(at 0 0 0)
			(layer "F.Fab")
			(hide yes)
			(effects
				(font
					(size 1 1)
					(thickness 0.15)
				)
			)
		)
		(property "Val" "330R"
			(at 0 0 0)
			(layer "F.Fab")
			(hide yes)
			(effects
				(font
					(size 1 1)
					(thickness 0.15)
				)
			)
		)
		(sheetname "Supply")
		(sheetfile "supply.kicad_sch")
		(attr smd)
		(fp_rect
			(start -0.93 -0.47)
			(end 0.93 0.47)
			(stroke
				(width 0.05)
				(type solid)
			)
			(fill no)
			(layer "F.CrtYd")
		)
		(fp_rect
			(start -0.5 -0.25)
			(end 0.5 0.25)
			(stroke
				(width 0.15)
				(type solid)
			)
			(fill no)
			(layer "F.Fab")
		)
		(pad "1" smd roundrect
			(at -0.485 0)
			(size 0.59 0.64)
			(layers "F.Cu" "F.Mask" "F.Paste")
			(roundrect_rratio 0.25)
			(net 553 "Net-(PWR2-Pad2)")
			(pintype "passive")
		)
		(pad "2" smd roundrect
			(at 0.485 0)
			(size 0.59 0.64)
			(layers "F.Cu" "F.Mask" "F.Paste")
			(roundrect_rratio 0.25)
			(net 234 "Net-(Q8-D)")
			(pintype "passive")
		)
	)
	(footprint "antmicro-footprints:R_0402_1005Metric"
		(layer "F.Cu")
		(at 137.1 64.7 180)
		(descr "Resistor SMD 0402")
		(tags "resistor SMD 0402")
		(property "Reference" "R154"
			(at 0.9 -2.3 180)
			(layer "F.SilkS")
			(effects
				(font
					(size 0.7 0.7)
					(thickness 0.15)
				)
				(justify left bottom)
			)
		)
		(property "Value" "R_10R_0402"
			(at 0 1.4 180)
			(layer "F.Fab")
			(effects
				(font
					(size 0.7 0.7)
					(thickness 0.15)
				)
				(justify left bottom)
			)
		)
		(property "Description" "10R resistor in 0402 package with 1% tolerance"
			(at 0 0 180)
			(layer "F.Fab")
			(hide yes)
			(effects
				(font
					(size 1.27 1.27)
					(thickness 0.15)
				)
			)
		)
		(property "Author" "Antmicro"
			(at 274.2 129.4 0)
			(layer "F.Fab")
			(hide yes)
			(effects
				(font
					(size 1 1)
					(thickness 0.15)
				)
			)
		)
		(property "License" "Apache-2.0"
			(at 274.2 129.4 0)
			(layer "F.Fab")
			(hide yes)
			(effects
				(font
					(size 1 1)
					(thickness 0.15)
				)
			)
		)
		(property "MPN" "CR0402-FX-10R0GLF"
			(at 274.2 129.4 0)
			(layer "F.Fab")
			(hide yes)
			(effects
				(font
					(size 1 1)
					(thickness 0.15)
				)
			)
		)
		(property "Manufacturer" "Bourns"
			(at 274.2 129.4 0)
			(layer "F.Fab")
			(hide yes)
			(effects
				(font
					(size 1 1)
					(thickness 0.15)
				)
			)
		)
		(property "Tolerance" "1%"
			(at 274.2 129.4 0)
			(layer "F.Fab")
			(hide yes)
			(effects
				(font
					(size 1 1)
					(thickness 0.15)
				)
			)
		)
		(property "Val" "10R"
			(at 274.2 129.4 0)
			(layer "F.Fab")
			(hide yes)
			(effects
				(font
					(size 1 1)
					(thickness 0.15)
				)
			)
		)
		(sheetname "Supply")
		(sheetfile "supply.kicad_sch")
		(attr smd)
		(fp_rect
			(start -0.93 -0.47)
			(end 0.93 0.47)
			(stroke
				(width 0.05)
				(type solid)
			)
			(fill no)
			(layer "F.CrtYd")
		)
		(fp_rect
			(start -0.5 -0.25)
			(end 0.5 0.25)
			(stroke
				(width 0.15)
				(type solid)
			)
			(fill no)
			(layer "F.Fab")
		)
		(pad "1" smd roundrect
			(at -0.485 0 180)
			(size 0.59 0.64)
			(layers "F.Cu" "F.Mask" "F.Paste")
			(roundrect_rratio 0.25)
			(net 633 "/Supply/0V6_REG")
			(pintype "passive")
		)
		(pad "2" smd roundrect
			(at 0.485 0 180)
			(size 0.59 0.64)
			(layers "F.Cu" "F.Mask" "F.Paste")
			(roundrect_rratio 0.25)
			(net 635 "/Supply/0V6_FB")
			(pintype "passive")
		)
	)
)
